(kicad_pcb
	(version 20241229)
	(generator "pcbnew")
	(generator_version "9.0")
	(general
		(thickness 1.63)
		(legacy_teardrops no)
	)
	(paper "A4")
	(title_block
		(title "CM4 Baseboard")
		(date "2026-01-05")
		(rev "1.1.1")
		(company "Antmicro Ltd")
		(comment 1 "www.antmicro.com")
		(comment 9 "footprints 165-168 of 506")
	)
	(layers
		(0 "F.Cu" signal)
		(4 "In1.Cu" power)
		(6 "In2.Cu" power)
		(8 "In3.Cu" signal)
		(10 "In4.Cu" signal)
		(2 "B.Cu" signal)
		(9 "F.Adhes" user "F.Adhesive")
		(11 "B.Adhes" user "B.Adhesive")
		(13 "F.Paste" user)
		(15 "B.Paste" user)
		(5 "F.SilkS" user "F.Silkscreen")
		(7 "B.SilkS" user "B.Silkscreen")
		(1 "F.Mask" user)
		(3 "B.Mask" user)
		(17 "Dwgs.User" user "User.Drawings")
		(19 "Cmts.User" user "User.Comments")
		(21 "Eco1.User" user "User.Eco1")
		(23 "Eco2.User" user "User.Eco2")
		(25 "Edge.Cuts" user)
		(27 "Margin" user)
		(31 "F.CrtYd" user "F.Courtyard")
		(29 "B.CrtYd" user "B.Courtyard")
		(35 "F.Fab" user)
		(33 "B.Fab" user)
	)
	(footprint "antmicro-footprints:R_0402_1005Metric"
		(layer "F.Cu")
		(at 110.951464 157.0515 180)
		(descr "Resistor SMD 0402")
		(tags "resistor SMD 0402")
		(property "Reference" "R227"
			(at 1.873502 -2.425 180)
			(layer "F.SilkS")
			(effects
				(font
					(size 0.7 0.7)
					(thickness 0.15)
				)
				(justify left bottom)
			)
		)
		(property "Value" "R_0R_0402"
			(at -1.011843 1.772047 180)
			(layer "F.Fab")
			(effects
				(font
					(size 0.7 0.7)
					(thickness 0.15)
				)
				(justify left bottom)
			)
		)
		(property "Datasheet" "https://industrial.panasonic.com/cdbs/www-data/pdf/RDA0000/AOA0000C301.pdf"
			(at 0 0 180)
			(layer "F.Fab")
			(hide yes)
			(effects
				(font
					(size 1.27 1.27)
					(thickness 0.15)
				)
			)
		)
		(property "Manufacturer" "Panasonic"
			(at 0 0 180)
			(unlocked yes)
			(layer "F.Fab")
			(hide yes)
			(effects
				(font
					(size 1 1)
					(thickness 0.15)
				)
			)
		)
		(property "MPN" "ERJ2GE0R00X"
			(at 0 0 180)
			(unlocked yes)
			(layer "F.Fab")
			(hide yes)
			(effects
				(font
					(size 1 1)
					(thickness 0.15)
				)
			)
		)
		(property "Val" "0R"
			(at 0 0 180)
			(unlocked yes)
			(layer "F.Fab")
			(hide yes)
			(effects
				(font
					(size 1 1)
					(thickness 0.15)
				)
			)
		)
		(property "License" "Apache-2.0"
			(at 0 0 180)
			(unlocked yes)
			(layer "F.Fab")
			(hide yes)
			(effects
				(font
					(size 1 1)
					(thickness 0.15)
				)
			)
		)
		(property "Author" "Antmicro"
			(at 0 0 180)
			(unlocked yes)
			(layer "F.Fab")
			(hide yes)
			(effects
				(font
					(size 1 1)
					(thickness 0.15)
				)
			)
		)
		(property "Tolerance" "~"
			(at 0 0 180)
			(unlocked yes)
			(layer "F.Fab")
			(hide yes)
			(effects
				(font
					(size 1 1)
					(thickness 0.15)
				)
			)
		)
		(property "Current" "1A"
			(at 0 0 180)
			(unlocked yes)
			(layer "F.Fab")
			(hide yes)
			(effects
				(font
					(size 1 1)
					(thickness 0.15)
				)
			)
		)
		(sheetname "/Compute module/")
		(sheetfile "compute-module.kicad_sch")
		(attr smd)
		(fp_rect
			(start -0.925 -0.47)
			(end 0.925 0.47)
			(stroke
				(width 0.05)
				(type default)
			)
			(fill no)
			(layer "F.CrtYd")
		)
		(fp_rect
			(start -0.5 -0.25)
			(end 0.5 0.25)
			(stroke
				(width 0.15)
				(type solid)
			)
			(fill no)
			(layer "F.Fab")
		)
		(fp_text user "License: Apache-2.0"
			(at -0.95 5.169 180)
			(layer "F.Fab")
			(effects
				(font
					(size 0.7 0.7)
					(thickness 0.15)
				)
				(justify left bottom)
			)
		)
		(fp_text user "Author: Antmicro"
			(at -0.95 4.169 180)
			(layer "F.Fab")
			(effects
				(font
					(size 0.7 0.7)
					(thickness 0.15)
				)
				(justify left bottom)
			)
		)
		(fp_text user "${REFERENCE}"
			(at -0.95 3.168 180)
			(layer "F.Fab")
			(effects
				(font
					(size 0.7 0.7)
					(thickness 0.15)
				)
				(justify left bottom)
			)
		)
		(pad "1" smd roundrect
			(at -0.48 0 180)
			(size 0.59 0.64)
			(layers "F.Cu" "F.Mask" "F.Paste")
			(roundrect_rratio 0.25)
			(net 153 "/Compute module/T3_N")
			(pintype "passive")
		)
		(pad "2" smd roundrect
			(at 0.48 0 180)
			(size 0.59 0.64)
			(layers "F.Cu" "F.Mask" "F.Paste")
			(roundrect_rratio 0.25)
			(net 160 "/Compute module/NVMe.TX3_N")
			(pintype "passive")
		)
	)
	(footprint "antmicro-footprints:LED_0603_1608Metric_G"
		(layer "F.Cu")
		(at 75.583462 145.9865 180)
		(descr "LED SMD 0603 Green")
		(tags "LED SMD 0603 Green")
		(property "Reference" "D202"
			(at -1.2845 4.72 0)
			(layer "F.SilkS")
			(effects
				(font
					(size 0.7 0.7)
					(thickness 0.15)
				)
				(justify right bottom)
			)
		)
		(property "Value" "LED_G_0603_KP-1608CGCK"
			(at -0.001 1.599 0)
			(layer "F.Fab")
			(effects
				(font
					(size 0.7 0.7)
					(thickness 0.15)
				)
				(justify right bottom)
			)
		)
		(property "Datasheet" "http://www.kingbright.com/attachments/file/psearch//000/00/00/KP-1608CGCK(Ver.23B).pdf"
			(at 0 0 180)
			(layer "F.Fab")
			(hide yes)
			(effects
				(font
					(size 1.27 1.27)
					(thickness 0.15)
				)
			)
		)
		(property "MPN" "KP-1608CGCK"
			(at 0 0 180)
			(unlocked yes)
			(layer "F.Fab")
			(hide yes)
			(effects
				(font
					(size 1 1)
					(thickness 0.15)
				)
			)
		)
		(property "Manufacturer" "Kingbright"
			(at 0 0 180)
			(unlocked yes)
			(layer "F.Fab")
			(hide yes)
			(effects
				(font
					(size 1 1)
					(thickness 0.15)
				)
			)
		)
		(property "Color" "Green"
			(at 0 0 180)
			(unlocked yes)
			(layer "F.Fab")
			(hide yes)
			(effects
				(font
					(size 1 1)
					(thickness 0.15)
				)
			)
		)
		(property "Author" "Antmicro"
			(at 0 0 180)
			(unlocked yes)
			(layer "F.Fab")
			(hide yes)
			(effects
				(font
					(size 1 1)
					(thickness 0.15)
				)
			)
		)
		(property "License" "Apache-2.0"
			(at 0 0 180)
			(unlocked yes)
			(layer "F.Fab")
			(hide yes)
			(effects
				(font
					(size 1 1)
					(thickness 0.15)
				)
			)
		)
		(sheetname "/Compute module/")
		(sheetfile "compute-module.kicad_sch")
		(attr smd)
		(fp_line
			(start 0.22 0.35)
			(end -0.22 0.35)
			(stroke
				(width 0.15)
				(type solid)
			)
			(layer "F.SilkS")
		)
		(fp_line
			(start 0.22 -0.35)
			(end -0.22 -0.35)
			(stroke
				(width 0.15)
				(type solid)
			)
			(layer "F.SilkS")
		)
		(fp_line
			(start 0.105328 0.201008)
			(end 0.105328 -0.198992)
			(stroke
				(width 0.1)
				(type solid)
			)
			(layer "F.SilkS")
		)
		(fp_line
			(start 0.105328 0.201008)
			(end -0.094672 0.001008)
			(stroke
				(width 0.1)
				(type solid)
			)
			(layer "F.SilkS")
		)
		(fp_line
			(start 0.105328 0.001008)
			(end 0.24 0.001)
			(stroke
				(width 0.1)
				(type solid)
			)
			(layer "F.SilkS")
		)
		(fp_line
			(start -0.094672 0.201008)
			(end -0.094672 -0.198992)
			(stroke
				(width 0.1)
				(type solid)
			)
			(layer "F.SilkS")
		)
		(fp_line
			(start -0.094672 0.001008)
			(end 0.105328 -0.198992)
			(stroke
				(width 0.1)
				(type solid)
			)
			(layer "F.SilkS")
		)
		(fp_line
			(start -0.094672 0.001008)
			(end -0.24 0.001008)
			(stroke
				(width 0.1)
				(type solid)
			)
			(layer "F.SilkS")
		)
		(fp_line
			(start -1.18 -0.319)
			(end -1.18 0.321)
			(stroke
				(width 0.15)
				(type solid)
			)
			(layer "F.SilkS")
		)
		(fp_rect
			(start 1.25 0.65)
			(end -1.25 -0.65)
			(stroke
				(width 0.05)
				(type solid)
			)
			(fill no)
			(layer "F.CrtYd")
		)
		(fp_line
			(start 0.599 0)
			(end 0.201 0)
			(stroke
				(width 0.15)
				(type solid)
			)
			(layer "F.Fab")
		)
		(fp_line
			(start 0.201 0.2)
			(end 0.201 0)
			(stroke
				(width 0.15)
				(type solid)
			)
			(layer "F.Fab")
		)
		(fp_line
			(start 0.201 0)
			(end 0.201 -0.202)
			(stroke
				(width 0.15)
				(type solid)
			)
			(layer "F.Fab")
		)
		(fp_line
			(start 0.201 -0.202)
			(end -0.101 0)
			(stroke
				(width 0.15)
				(type solid)
			)
			(layer "F.Fab")
		)
		(fp_line
			(start -0.101 0)
			(end 0.201 0.2)
			(stroke
				(width 0.15)
				(type solid)
			)
			(layer "F.Fab")
		)
		(fp_line
			(start -0.199 0.2)
			(end -0.199 0.1)
			(stroke
				(width 0.15)
				(type solid)
			)
			(layer "F.Fab")
		)
		(fp_line
			(start -0.199 0)
			(end -0.597 0)
			(stroke
				(width 0.15)
				(type solid)
			)
			(layer "F.Fab")
		)
		(fp_line
			(start -0.199 -0.202)
			(end -0.199 0.1)
			(stroke
				(width 0.15)
				(type solid)
			)
			(layer "F.Fab")
		)
		(fp_rect
			(start 0.848 0.4)
			(end -0.85 -0.402)
			(stroke
				(width 0.15)
				(type solid)
			)
			(fill no)
			(layer "F.Fab")
		)
		(fp_text user "License: Apache-2.0"
			(at -1.4224 3.599 180)
			(layer "F.Fab")
			(effects
				(font
					(size 0.7 0.7)
					(thickness 0.15)
				)
				(justify left bottom)
			)
		)
		(fp_text user "${REFERENCE}"
			(at -1.4224 5.999 180)
			(layer "F.Fab")
			(effects
				(font
					(size 0.7 0.7)
					(thickness 0.15)
				)
				(justify left bottom)
			)
		)
		(fp_text user "Author: Antmicro"
			(at -1.4224 4.799 180)
			(layer "F.Fab")
			(effects
				(font
					(size 0.7 0.7)
					(thickness 0.15)
				)
				(justify left bottom)
			)
		)
		(pad "1" smd roundrect
			(at -0.7 0)
			(size 0.8 1)
			(layers "F.Cu" "F.Mask" "F.Paste")
			(roundrect_rratio 0.2)
			(net 467 "Net-(D202-C)")
			(pinfunction "C")
			(pintype "passive")
		)
		(pad "2" smd roundrect
			(at 0.7 0)
			(size 0.8 1)
			(layers "F.Cu" "F.Mask" "F.Paste")
			(roundrect_rratio 0.2)
			(net 468 "Net-(D202-A)")
			(pinfunction "A")
			(pintype "passive")
		)
	)
	(footprint "antmicro-footprints:TP_SMD_0.75mm"
		(layer "F.Cu")
		(at 74.842962 157.2915)
		(property "Reference" "TP301"
			(at 1.257038 0.7085 90)
			(layer "F.SilkS")
			(effects
				(font
					(size 0.7 0.7)
					(thickness 0.15)
				)
				(justify left bottom)
			)
		)
		(property "Value" "TP_0.75mm_SMD"
			(at 0 1.2 0)
			(layer "F.Fab")
			(effects
				(font
					(size 0.7 0.7)
					(thickness 0.15)
				)
				(justify left bottom)
			)
		)
		(property "MPN" ""
			(at 0 0 0)
			(unlocked yes)
			(layer "F.Fab")
			(hide yes)
			(effects
				(font
					(size 1 1)
					(thickness 0.15)
				)
			)
		)
		(property "Manufacturer" ""
			(at 0 0 0)
			(unlocked yes)
			(layer "F.Fab")
			(hide yes)
			(effects
				(font
					(size 1 1)
					(thickness 0.15)
				)
			)
		)
		(property "Author" "Antmicro"
			(at 0 0 0)
			(unlocked yes)
			(layer "F.Fab")
			(hide yes)
			(effects
				(font
					(size 1 1)
					(thickness 0.15)
				)
			)
		)
		(property "License" "Apache-2.0"
			(at 0 0 0)
			(unlocked yes)
			(layer "F.Fab")
			(hide yes)
			(effects
				(font
					(size 1 1)
					(thickness 0.15)
				)
			)
		)
		(sheetname "/Supply/")
		(sheetfile "supply.kicad_sch")
		(attr exclude_from_pos_files exclude_from_bom)
		(fp_circle
			(center 0 0)
			(end 0.475 0)
			(stroke
				(width 0.05)
				(type default)
			)
			(fill no)
			(layer "F.CrtYd")
		)
		(fp_text user "${REFERENCE}"
			(at -0.4 2.7 0)
			(layer "F.Fab")
			(effects
				(font
					(size 0.7 0.7)
					(thickness 0.15)
				)
				(justify left bottom)
			)
		)
		(fp_text user "License: Apache-2.0"
			(at -0.4 5.101 0)
			(layer "F.Fab")
			(effects
				(font
					(size 0.7 0.7)
					(thickness 0.15)
				)
				(justify left bottom)
			)
		)
		(fp_text user "Author: Antmicro"
			(at -0.4 3.901 0)
			(layer "F.Fab")
			(effects
				(font
					(size 0.7 0.7)
					(thickness 0.15)
				)
				(justify left bottom)
			)
		)
		(pad "1" smd circle
			(at 0 0)
			(size 0.75 0.75)
			(layers "F.Cu" "F.Mask")
			(net 43 "VCC")
			(pinfunction "1")
			(pintype "passive")
		)
	)
	(footprint "antmicro-footprints:USB-C_Receptacle_GCT_USB4105-GF-A"
		(layer "F.Cu")
		(at 79.780962 115.602 180)
		(property "Reference" "J902"
			(at -7.567 3.7555 90)
			(layer "F.SilkS")
			(effects
				(font
					(size 0.7 0.7)
					(thickness 0.15)
				)
				(justify right bottom)
			)
		)
		(property "Value" "USB-C_GCT_USB4105-GF-A"
			(at 0 5 0)
			(layer "F.Fab")
			(effects
				(font
					(size 0.7 0.7)
					(thickness 0.15)
				)
				(justify right bottom)
			)
		)
		(property "Datasheet" "https://gct.co/files/drawings/usb4105.pdf"
			(at 0 0 180)
			(layer "F.Fab")
			(hide yes)
			(effects
				(font
					(size 1.27 1.27)
					(thickness 0.15)
				)
			)
		)
		(property "Manufacturer" "GCT"
			(at 0 0 180)
			(unlocked yes)
			(layer "F.Fab")
			(hide yes)
			(effects
				(font
					(size 1 1)
					(thickness 0.15)
				)
			)
		)
		(property "MPN" "USB4105-GF-A"
			(at 0 0 180)
			(unlocked yes)
			(layer "F.Fab")
			(hide yes)
			(effects
				(font
					(size 1 1)
					(thickness 0.15)
				)
			)
		)
		(property "Author" "Antmicro"
			(at 0 0 180)
			(unlocked yes)
			(layer "F.Fab")
			(hide yes)
			(effects
				(font
					(size 1 1)
					(thickness 0.15)
				)
			)
		)
		(property "License" "Apache-2.0"
			(at 0 0 180)
			(unlocked yes)
			(layer "F.Fab")
			(hide yes)
			(effects
				(font
					(size 1 1)
					(thickness 0.15)
				)
			)
		)
		(sheetname "/USB/")
		(sheetfile "usb.kicad_sch")
		(attr smd)
		(fp_line
			(start 4.788 3.854)
			(end 4.788 2.575)
			(stroke
				(width 0.15)
				(type solid)
			)
			(layer "F.SilkS")
		)
		(fp_line
			(start 4.788 -1.395)
			(end 4.788 -0.145)
			(stroke
				(width 0.15)
				(type solid)
			)
			(layer "F.SilkS")
		)
		(fp_line
			(start -4.79 3.854)
			(end 4.788 3.854)
			(stroke
				(width 0.15)
				(type solid)
			)
			(layer "F.SilkS")
		)
		(fp_line
			(start -4.79 2.575)
			(end -4.79 3.854)
			(stroke
				(width 0.15)
				(type solid)
			)
			(layer "F.SilkS")
		)
		(fp_line
			(start -4.79 -1.395)
			(end -4.79 -0.145)
			(stroke
				(width 0.15)
				(type solid)
			)
			(layer "F.SilkS")
		)
		(fp_circle
			(center -3.8 -4.27071)
			(end -3.75 -4.22071)
			(stroke
				(width 0.15)
				(type solid)
			)
			(fill yes)
			(layer "F.SilkS")
		)
		(fp_rect
			(start -5.1 -4.4)
			(end 5.1 3.9)
			(stroke
				(width 0.05)
				(type solid)
			)
			(fill no)
			(layer "F.CrtYd")
		)
		(fp_line
			(start 4.788 3.854)
			(end -4.79 3.854)
			(stroke
				(width 0.15)
				(type solid)
			)
			(layer "F.Fab")
		)
		(fp_line
			(start 4.788 -3.676)
			(end 4.788 3.854)
			(stroke
				(width 0.15)
				(type solid)
			)
			(layer "F.Fab")
		)
		(fp_line
			(start -4.702 3.854)
			(end 4.788 3.854)
			(stroke
				(width 0.15)
				(type solid)
			)
			(layer "F.Fab")
		)
		(fp_line
			(start -4.79 3.854)
			(end -4.79 -3.676)
			(stroke
				(width 0.15)
				(type solid)
			)
			(layer "F.Fab")
		)
		(fp_line
			(start -4.79 -3.676)
			(end 4.788 -3.676)
			(stroke
				(width 0.15)
				(type solid)
			)
			(layer "F.Fab")
		)
		(fp_text user "License: Apache-2.0"
			(at -4.79 8.855 180)
			(layer "F.Fab")
			(effects
				(font
					(size 0.7 0.7)
					(thickness 0.15)
				)
				(justify left bottom)
			)
		)
		(fp_text user "PCB-EDGE"
			(at -4.79 5.853 180)
			(layer "F.Fab")
			(effects
				(font
					(size 0.7 0.7)
					(thickness 0.15)
				)
				(justify left bottom)
			)
		)
		(fp_text user "Author: Antmicro"
			(at -4.79 7.853 180)
			(layer "F.Fab")
			(effects
				(font
					(size 0.7 0.7)
					(thickness 0.15)
				)
				(justify left bottom)
			)
		)
		(fp_text user "${REFERENCE}"
			(at -4.79 6.853 180)
			(layer "F.Fab")
			(effects
				(font
					(size 0.7 0.7)
					(thickness 0.15)
				)
				(justify left bottom)
			)
		)
		(pad "" np_thru_hole circle
			(at -2.891 -2.426 180)
			(size 0.65 0.65)
			(drill 0.65)
			(layers "*.Cu" "*.Mask")
		)
		(pad "" np_thru_hole circle
			(at 2.89 -2.426 180)
			(size 0.65 0.65)
			(drill 0.65)
			(layers "*.Cu" "*.Mask")
		)
		(pad "A1" smd roundrect
			(at -3.202 -3.5 180)
			(size 0.6 1.15)
			(layers "F.Cu" "F.Mask" "F.Paste")
			(roundrect_rratio 0.25)
			(net 3 "GND")
			(pinfunction "GND")
			(pintype "power_in")
		)
		(pad "A4" smd roundrect
			(at -2.4 -3.5 180)
			(size 0.6 1.15)
			(layers "F.Cu" "F.Mask" "F.Paste")
			(roundrect_rratio 0.25)
			(net 26 "/USB/USBD_VBUS")
			(pinfunction "VBUS")
			(pintype "power_in")
		)
		(pad "A5" smd roundrect
			(at -1.25 -3.5 180)
			(size 0.3 1.15)
			(layers "F.Cu" "F.Mask" "F.Paste")
			(roundrect_rratio 0.25)
			(net 207 "/USB/USBD_CC1")
			(pinfunction "CC_{1}")
			(pintype "bidirectional")
		)
		(pad "A6" smd roundrect
			(at -0.25 -3.5 180)
			(size 0.3 1.15)
			(layers "F.Cu" "F.Mask" "F.Paste")
			(roundrect_rratio 0.25)
			(net 209 "/USB/DD_P")
			(pinfunction "D_{A}+")
			(pintype "bidirectional")
		)
		(pad "A7" smd roundrect
			(at 0.248 -3.5 180)
			(size 0.3 1.15)
			(layers "F.Cu" "F.Mask" "F.Paste")
			(roundrect_rratio 0.25)
			(net 210 "/USB/DD_N")
			(pinfunction "D_{A}-")
			(pintype "bidirectional")
		)
		(pad "A8" smd roundrect
			(at 1.249 -3.5 180)
			(size 0.3 1.15)
			(layers "F.Cu" "F.Mask" "F.Paste")
			(roundrect_rratio 0.25)
			(net 324 "unconnected-(J902-SBU_{1}-PadA8)")
			(pinfunction "SBU_{1}")
			(pintype "bidirectional+no_connect")
		)
		(pad "A9" smd roundrect
			(at 2.398 -3.5 180)
			(size 0.6 1.15)
			(layers "F.Cu" "F.Mask" "F.Paste")
			(roundrect_rratio 0.25)
			(net 26 "/USB/USBD_VBUS")
			(pinfunction "VBUS")
			(pintype "passive")
		)
		(pad "A12" smd roundrect
			(at 3.2 -3.5 180)
			(size 0.6 1.15)
			(layers "F.Cu" "F.Mask" "F.Paste")
			(roundrect_rratio 0.25)
			(net 3 "GND")
			(pinfunction "GND")
			(pintype "passive")
		)
		(pad "B1" smd roundrect
			(at 3.2 -3.5 180)
			(size 0.6 1.15)
			(layers "F.Cu" "F.Mask" "F.Paste")
			(roundrect_rratio 0.25)
			(net 3 "GND")
			(pinfunction "GND")
			(pintype "passive")
		)
		(pad "B4" smd roundrect
			(at 2.398 -3.5 180)
			(size 0.6 1.15)
			(layers "F.Cu" "F.Mask" "F.Paste")
			(roundrect_rratio 0.25)
			(net 26 "/USB/USBD_VBUS")
			(pinfunction "VBUS")
			(pintype "passive")
		)
		(pad "B5" smd roundrect
			(at 1.749 -3.5 180)
			(size 0.3 1.15)
			(layers "F.Cu" "F.Mask" "F.Paste")
			(roundrect_rratio 0.25)
			(net 208 "/USB/USBD_CC2")
			(pinfunction "CC_{2}")
			(pintype "bidirectional")
		)
		(pad "B6" smd roundrect
			(at 0.748 -3.5 180)
			(size 0.3 1.15)
			(layers "F.Cu" "F.Mask" "F.Paste")
			(roundrect_rratio 0.25)
			(net 209 "/USB/DD_P")
			(pinfunction "D_{B}+")
			(pintype "bidirectional")
		)
		(pad "B7" smd roundrect
			(at -0.75 -3.5 180)
			(size 0.3 1.15)
			(layers "F.Cu" "F.Mask" "F.Paste")
			(roundrect_rratio 0.25)
			(net 210 "/USB/DD_N")
			(pinfunction "D_{B}-")
			(pintype "bidirectional")
		)
		(pad "B8" smd roundrect
			(at -1.75 -3.5 180)
			(size 0.3 1.15)
			(layers "F.Cu" "F.Mask" "F.Paste")
			(roundrect_rratio 0.25)
			(net 323 "unconnected-(J902-SBU_{2}-PadB8)")
			(pinfunction "SBU_{2}")
			(pintype "bidirectional+no_connect")
		)
		(pad "B9" smd roundrect
			(at -2.4 -3.5 180)
			(size 0.6 1.15)
			(layers "F.Cu" "F.Mask" "F.Paste")
			(roundrect_rratio 0.25)
			(net 26 "/USB/USBD_VBUS")
			(pinfunction "VBUS")
			(pintype "passive")
		)
		(pad "B12" smd roundrect
			(at -3.202 -3.5 180)
			(size 0.6 1.15)
			(layers "F.Cu" "F.Mask" "F.Paste")
			(roundrect_rratio 0.25)
			(net 3 "GND")
			(pinfunction "GND")
			(pintype "passive")
		)
		(pad "SH" thru_hole oval
			(at -4.321 -2.926 180)
			(size 1.05 2.1)
			(drill oval 0.6 1.7)
			(layers "*.Cu" "*.Mask")
			(remove_unused_layers no)
			(net 3 "GND")
			(pinfunction "SH")
			(pintype "passive")
		)
		(pad "SH" thru_hole oval
			(at -4.321 1.255 180)
			(size 1 2)
			(drill oval 0.6 1.4)
			(layers "*.Cu" "*.Mask")
			(remove_unused_layers no)
			(net 3 "GND")
			(pinfunction "SH")
			(pintype "passive")
		)
		(pad "SH" thru_hole oval
			(at 4.32 -2.926 180)
			(size 1.05 2.1)
			(drill oval 0.6 1.7)
			(layers "*.Cu" "*.Mask")
			(remove_unused_layers no)
			(net 3 "GND")
			(pinfunction "SH")
			(pintype "passive")
		)
		(pad "SH" thru_hole oval
			(at 4.32 1.255 180)
			(size 1 2)
			(drill oval 0.6 1.4)
			(layers "*.Cu" "*.Mask")
			(remove_unused_layers no)
			(net 3 "GND")
			(pinfunction "SH")
			(pintype "passive")
		)
	)
)
